# BASEBOARD_FAB2 (Tioga Pass) — schematic netlist excerpt (pin names and nets, part order shuffled) for the footprints in the layout excerpt that follows; sources: Cadence DE-HDL packaged netlist, KiCad conversion of Wiwynn_Tioga_Pass_MB.brd

C5P35  CAP  47UF 4V 20% X6S  pkg 0805  page 42 : A = PVCCIN_CPU0 ; B = GND
C2L21  CAP_A  0.01UF 25V 10% X7R  pkg 0402V  page 173 : A = SATA6G_P7_TX_C_DN ; B = SATA6G_PCH_PCIE_UP_SATA_TXN<7>
C3L10  CAP  10UF 16V 10% X6S  pkg 0805  page 236 : A = VR_FET_SW_P12V_STBY_PVDDQ_DEF ; B = GND

(kicad_pcb
	(version 20260206)
	(generator "pcbnew")
	(generator_version "10.0")
	(general
		(thickness 1.6)
		(legacy_teardrops no)
	)
	(paper "A4")
	(title_block
		(title "Wiwynn_Tioga_Pass_MB.brd")
		(comment 1 "Tioga Pass / footprints 2336-2338 of 4770")
	)
	(layers
		(0 "F.Cu" signal "TOP")
		(4 "In1.Cu" signal "L2GND")
		(6 "In2.Cu" signal "L3")
		(8 "In3.Cu" signal "L4GND")
		(10 "In4.Cu" signal "L5")
		(12 "In5.Cu" signal "L6GND")
		(14 "In6.Cu" signal "L7VCC")
		(16 "In7.Cu" signal "L8VCC")
		(18 "In8.Cu" signal "L9GND")
		(20 "In9.Cu" signal "L10")
		(22 "In10.Cu" signal "L11GND")
		(24 "In11.Cu" signal "L12")
		(26 "In12.Cu" signal "L13GND")
		(2 "B.Cu" signal "BOTTOM")
		(9 "F.Adhes" user "F.Adhesive")
		(11 "B.Adhes" user "B.Adhesive")
		(13 "F.Paste" user "Package Geometry/Pastemask Top")
		(15 "B.Paste" user "Package Geometry/Pastemask Bottom")
		(5 "F.SilkS" user "Ref Des/Silkscreen Top")
		(7 "B.SilkS" user "Ref Des/Silkscreen Bottom")
		(1 "F.Mask" user "Board Geometry/Soldermask Top")
		(3 "B.Mask" user "Board Geometry/Soldermask Bottom")
		(17 "Dwgs.User" user "User.Drawings")
		(19 "Cmts.User" user "User.Comments")
		(21 "Eco1.User" user "User.Eco1")
		(23 "Eco2.User" user "User.Eco2")
		(25 "Edge.Cuts" user "Board Geometry/Outline")
		(27 "Margin" user)
		(31 "F.CrtYd" user "Package Geometry/Place Bound Top")
		(29 "B.CrtYd" user "Package Geometry/Place Bound Bottom")
		(35 "F.Fab" user "Ref Des/Assembly Top")
		(33 "B.Fab" user "Ref Des/Assembly Bottom")
	)
	(footprint ""
		(layer "B.Cu")
		(at 388.154672 -154.721306)
		(property "Reference" "C3L10"
			(at 0 0 0)
			(layer "B.SilkS")
			(hide yes)
			(effects
				(font
					(size 1.27 1.27)
				)
				(justify mirror)
			)
		)
		(property "Value" ""
			(at 0 0 0)
			(layer "B.Fab")
			(effects
				(font
					(size 1.27 1.27)
				)
				(justify mirror)
			)
		)
		(duplicate_pad_numbers_are_jumpers no)
		(fp_poly
			(pts
				(xy 0.7239 -0.2159) (xy -0.7239 -0.2159) (xy -0.7239 1.9939) (xy 0.7239 1.9939)
			)
			(stroke
				(width 0)
				(type default)
			)
			(fill no)
			(layer "B.CrtYd")
		)
		(fp_line
			(start -0.7239 -0.2159)
			(end 0.7239 -0.2159)
			(stroke
				(width 0.1)
				(type default)
			)
			(layer "B.Fab")
		)
		(fp_line
			(start -0.7239 1.9939)
			(end -0.7239 -0.2159)
			(stroke
				(width 0.1)
				(type default)
			)
			(layer "B.Fab")
		)
		(fp_line
			(start 0.7239 -0.2159)
			(end 0.7239 1.9939)
			(stroke
				(width 0.1)
				(type default)
			)
			(layer "B.Fab")
		)
		(fp_line
			(start 0.7239 1.9939)
			(end -0.7239 1.9939)
			(stroke
				(width 0.1)
				(type default)
			)
			(layer "B.Fab")
		)
		(pad "1" smd rect
			(at 0 0 180)
			(size 1.27 1.016)
			(layers "B.Cu" "B.Mask" "B.Paste")
			(net "VR_FET_SW_P12V_STBY_PVDDQ_DEF")
		)
		(pad "2" smd rect
			(at 0 1.778 180)
			(size 1.27 1.016)
			(layers "B.Cu" "B.Mask" "B.Paste")
			(net "GND")
		)
		(zone
			(layer "B.Cu")
			(hatch none 0.5)
			(connect_pads
				(clearance 0)
			)
			(min_thickness 0.25)
			(keepout
				(tracks not_allowed)
				(vias allowed)
				(pads allowed)
				(copperpour not_allowed)
				(footprints allowed)
			)
			(placement
				(enabled no)
				(sheetname "")
			)
			(fill
				(thermal_gap 0.5)
				(thermal_bridge_width 0.5)
				(island_removal_mode 0)
			)
			(polygon
				(pts
					(xy 388.789672 -154.213306) (xy 387.519672 -154.213306) (xy 387.519672 -153.451306) (xy 388.789672 -153.451306)
				)
			)
		)
	)
	(footprint ""
		(layer "B.Cu")
		(at 262.206486 -73.51014)
		(property "Reference" "C5P35"
			(at 0 0 0)
			(layer "B.SilkS")
			(hide yes)
			(effects
				(font
					(size 1.27 1.27)
				)
				(justify mirror)
			)
		)
		(property "Value" ""
			(at 0 0 0)
			(layer "B.Fab")
			(effects
				(font
					(size 1.27 1.27)
				)
				(justify mirror)
			)
		)
		(duplicate_pad_numbers_are_jumpers no)
		(fp_poly
			(pts
				(xy 0.7239 -0.2159) (xy -0.7239 -0.2159) (xy -0.7239 1.9939) (xy 0.7239 1.9939)
			)
			(stroke
				(width 0)
				(type default)
			)
			(fill no)
			(layer "B.CrtYd")
		)
		(fp_line
			(start -0.7239 -0.2159)
			(end 0.7239 -0.2159)
			(stroke
				(width 0.1)
				(type default)
			)
			(layer "B.Fab")
		)
		(fp_line
			(start -0.7239 1.9939)
			(end -0.7239 -0.2159)
			(stroke
				(width 0.1)
				(type default)
			)
			(layer "B.Fab")
		)
		(fp_line
			(start 0.7239 -0.2159)
			(end 0.7239 1.9939)
			(stroke
				(width 0.1)
				(type default)
			)
			(layer "B.Fab")
		)
		(fp_line
			(start 0.7239 1.9939)
			(end -0.7239 1.9939)
			(stroke
				(width 0.1)
				(type default)
			)
			(layer "B.Fab")
		)
		(pad "1" smd rect
			(at 0 0 180)
			(size 1.27 1.016)
			(layers "B.Cu" "B.Mask" "B.Paste")
			(net "PVCCIN_CPU0")
		)
		(pad "2" smd rect
			(at 0 1.778 180)
			(size 1.27 1.016)
			(layers "B.Cu" "B.Mask" "B.Paste")
			(net "GND")
		)
		(zone
			(layer "B.Cu")
			(hatch none 0.5)
			(connect_pads
				(clearance 0)
			)
			(min_thickness 0.25)
			(keepout
				(tracks not_allowed)
				(vias allowed)
				(pads allowed)
				(copperpour not_allowed)
				(footprints allowed)
			)
			(placement
				(enabled no)
				(sheetname "")
			)
			(fill
				(thermal_gap 0.5)
				(thermal_bridge_width 0.5)
				(island_removal_mode 0)
			)
			(polygon
				(pts
					(xy 262.841486 -73.00214) (xy 261.571486 -73.00214) (xy 261.571486 -72.24014) (xy 262.841486 -72.24014)
				)
			)
		)
	)
	(footprint ""
		(layer "B.Cu")
		(at 409.6004 -147.955 -90)
		(property "Reference" "C2L21"
			(at 0 0 90)
			(layer "B.SilkS")
			(hide yes)
			(effects
				(font
					(size 1.27 1.27)
				)
				(justify mirror)
			)
		)
		(property "Value" ""
			(at 0 0 90)
			(layer "B.Fab")
			(effects
				(font
					(size 1.27 1.27)
				)
				(justify mirror)
			)
		)
		(duplicate_pad_numbers_are_jumpers no)
		(fp_poly
			(pts
				(xy -0.3048 -0.1016) (xy -0.3048 0.9906) (xy 0.3048 0.9906) (xy 0.3048 -0.1016)
			)
			(stroke
				(width 0)
				(type default)
			)
			(fill no)
			(layer "B.CrtYd")
		)
		(fp_line
			(start -0.3048 0.9906)
			(end -0.3048 -0.1016)
			(stroke
				(width 0.1)
				(type default)
			)
			(layer "B.Fab")
		)
		(fp_line
			(start 0.3048 0.9906)
			(end -0.3048 0.9906)
			(stroke
				(width 0.1)
				(type default)
			)
			(layer "B.Fab")
		)
		(fp_line
			(start -0.3048 -0.1016)
			(end 0.3048 -0.1016)
			(stroke
				(width 0.1)
				(type default)
			)
			(layer "B.Fab")
		)
		(fp_line
			(start 0.3048 -0.1016)
			(end 0.3048 0.9906)
			(stroke
				(width 0.1)
				(type default)
			)
			(layer "B.Fab")
		)
		(pad "1" smd rect
			(at 0 0 90)
			(size 0.508 0.508)
			(layers "B.Cu" "B.Mask" "B.Paste")
			(net "SATA6G_P7_TX_C_DN")
		)
		(pad "2" smd rect
			(at 0 0.889 90)
			(size 0.508 0.508)
			(layers "B.Cu" "B.Mask" "B.Paste")
			(net "SATA6G_PCH_PCIE_UP_SATA_TXN<7>")
		)
		(zone
			(layer "B.Cu")
			(hatch none 0.5)
			(connect_pads
				(clearance 0)
			)
			(min_thickness 0.25)
			(keepout
				(tracks not_allowed)
				(vias allowed)
				(pads allowed)
				(copperpour not_allowed)
				(footprints allowed)
			)
			(placement
				(enabled no)
				(sheetname "")
			)
			(fill
				(thermal_gap 0.5)
				(thermal_bridge_width 0.5)
				(island_removal_mode 0)
			)
			(polygon
				(pts
					(xy 408.9654 -147.701) (xy 408.9654 -148.209) (xy 409.3464 -148.209) (xy 409.3464 -147.701)
				)
			)
		)
		(zone
			(layer "B.Cu")
			(hatch none 0.5)
			(connect_pads
				(clearance 0)
			)
			(min_thickness 0.25)
			(keepout
				(tracks allowed)
				(vias not_allowed)
				(pads allowed)
				(copperpour not_allowed)
				(footprints allowed)
			)
			(placement
				(enabled no)
				(sheetname "")
			)
			(fill
				(thermal_gap 0.5)
				(thermal_bridge_width 0.5)
				(island_removal_mode 0)
			)
			(polygon
				(pts
					(xy 409.3464 -147.701) (xy 409.3464 -148.209) (xy 408.9654 -148.209) (xy 408.9654 -147.701)
				)
			)
		)
	)
)
